(kicad_pcb
	(version 20260206)
	(generator "pcbnew")
	(generator_version "10.0")
	(general
		(thickness 1.6)
		(legacy_teardrops no)
	)
	(paper "A4")
	(title_block
		(title "v1-chassis-manager — T6M_CM_d_v01_1031_1645.brd")
		(comment 1 "Open CloudServer (Microsoft) / footprints 1271-1276 of 2512")
	)
	(layers
		(0 "F.Cu" signal "TOP")
		(4 "In1.Cu" signal "GND1")
		(6 "In2.Cu" signal "IN1")
		(8 "In3.Cu" signal "VCC1")
		(10 "In4.Cu" signal "VCC2")
		(12 "In5.Cu" signal "GND2")
		(14 "In6.Cu" signal "IN2")
		(16 "In7.Cu" signal "IN3")
		(18 "In8.Cu" signal "GND3")
		(2 "B.Cu" signal "BOTTOM")
		(9 "F.Adhes" user "F.Adhesive")
		(11 "B.Adhes" user "B.Adhesive")
		(13 "F.Paste" user "Package Geometry/Pastemask Top")
		(15 "B.Paste" user "Package Geometry/Pastemask Bottom")
		(5 "F.SilkS" user "Ref Des/Silkscreen Top")
		(7 "B.SilkS" user "Ref Des/Silkscreen Bottom")
		(1 "F.Mask" user "Board Geometry/Soldermask Top")
		(3 "B.Mask" user "Board Geometry/Soldermask Bottom")
		(17 "Dwgs.User" user "User.Drawings")
		(19 "Cmts.User" user "User.Comments")
		(21 "Eco1.User" user "User.Eco1")
		(23 "Eco2.User" user "User.Eco2")
		(25 "Edge.Cuts" user "Board Geometry/Outline")
		(27 "Margin" user)
		(31 "F.CrtYd" user "Package Geometry/Place Bound Top")
		(29 "B.CrtYd" user "Package Geometry/Place Bound Bottom")
		(35 "F.Fab" user "Ref Des/Assembly Top")
		(33 "B.Fab" user "Ref Des/Assembly Bottom")
	)
	(footprint ""
		(layer "F.Cu")
		(at 155.476956 -20.568412 90)
		(property "Reference" "J5"
			(at -1.866138 3.43154 90)
			(unlocked yes)
			(layer "F.SilkS")
			(effects
				(font
					(size 0.7874 0.5842)
					(thickness 0.1524)
				)
				(justify left)
			)
		)
		(property "Value" ""
			(at 0 0 90)
			(layer "F.Fab")
			(effects
				(font
					(size 1.27 1.27)
				)
			)
		)
		(duplicate_pad_numbers_are_jumpers no)
		(fp_line
			(start 4.99999 -2.100072)
			(end -4.99999 -2.100072)
			(stroke
				(width 0.1524)
				(type default)
			)
			(layer "F.SilkS")
		)
		(fp_line
			(start -4.99999 -2.100072)
			(end -4.99999 0)
			(stroke
				(width 0.1524)
				(type default)
			)
			(layer "F.SilkS")
		)
		(fp_line
			(start 4.500118 -1.599946)
			(end 4.500118 2.100072)
			(stroke
				(width 0.1524)
				(type default)
			)
			(layer "F.SilkS")
		)
		(fp_line
			(start -2.3876 -1.599946)
			(end 4.500118 -1.599946)
			(stroke
				(width 0.1524)
				(type default)
			)
			(layer "F.SilkS")
		)
		(fp_line
			(start -4.500118 -1.599946)
			(end -3.6068 -1.599946)
			(stroke
				(width 0.1524)
				(type default)
			)
			(layer "F.SilkS")
		)
		(fp_line
			(start -4.99999 0)
			(end -4.99999 2.599944)
			(stroke
				(width 0.1524)
				(type default)
			)
			(layer "F.SilkS")
		)
		(fp_line
			(start 4.500118 2.100072)
			(end 1.999996 2.100072)
			(stroke
				(width 0.1524)
				(type default)
			)
			(layer "F.SilkS")
		)
		(fp_line
			(start 1.999996 2.100072)
			(end 1.999996 2.599944)
			(stroke
				(width 0.1524)
				(type default)
			)
			(layer "F.SilkS")
		)
		(fp_line
			(start -1.999996 2.100072)
			(end -4.500118 2.100072)
			(stroke
				(width 0.1524)
				(type default)
			)
			(layer "F.SilkS")
		)
		(fp_line
			(start -4.500118 2.100072)
			(end -4.500118 -1.599946)
			(stroke
				(width 0.1524)
				(type default)
			)
			(layer "F.SilkS")
		)
		(fp_line
			(start 4.99999 2.599944)
			(end 4.99999 -2.100072)
			(stroke
				(width 0.1524)
				(type default)
			)
			(layer "F.SilkS")
		)
		(fp_line
			(start -1.999996 2.599944)
			(end -1.999996 2.100072)
			(stroke
				(width 0.1524)
				(type default)
			)
			(layer "F.SilkS")
		)
		(fp_line
			(start -4.99999 2.599944)
			(end 4.99999 2.599944)
			(stroke
				(width 0.1524)
				(type default)
			)
			(layer "F.SilkS")
		)
		(fp_poly
			(pts
				(xy 2.959354 4.18084) (xy 3.721354 5.70484) (xy 2.197354 5.70484)
			)
			(stroke
				(width 0)
				(type default)
			)
			(fill yes)
			(layer "F.SilkS")
		)
		(fp_poly
			(pts
				(xy -3.7084 0.1778) (xy 3.683 0.1778) (xy 3.683 1.6256) (xy -3.7084 1.6256)
			)
			(stroke
				(width 0)
				(type default)
			)
			(fill no)
			(layer "B.CrtYd")
		)
		(fp_poly
			(pts
				(arc
					(start -2.9972 -1.7526)
					(mid -3.607857 -1.499657)
					(end -3.8608 -0.889)
				)
				(arc
					(start -3.8608 -0.889)
					(mid -3.615297 -0.296303)
					(end -3.0226 -0.0508)
				)
				(arc
					(start -2.9972 -0.0508)
					(mid -2.1463 -0.9017)
					(end -2.9972 -1.7526)
				)
			)
			(stroke
				(width 0)
				(type default)
			)
			(fill no)
			(layer "B.CrtYd")
		)
		(fp_rect
			(start -4.99999 2.599944)
			(end 4.99999 -2.100072)
			(stroke
				(width 0)
				(type default)
			)
			(fill no)
			(layer "F.CrtYd")
		)
		(fp_line
			(start 4.99999 -2.100072)
			(end -4.99999 -2.100072)
			(stroke
				(width 0.1)
				(type default)
			)
			(layer "F.Fab")
		)
		(fp_line
			(start -4.99999 -2.100072)
			(end -4.99999 0)
			(stroke
				(width 0.1)
				(type default)
			)
			(layer "F.Fab")
		)
		(fp_line
			(start 4.500118 -1.599946)
			(end 4.500118 2.100072)
			(stroke
				(width 0.1)
				(type default)
			)
			(layer "F.Fab")
		)
		(fp_line
			(start -3.6576 -1.599946)
			(end 4.500118 -1.599946)
			(stroke
				(width 0.1)
				(type default)
			)
			(layer "F.Fab")
		)
		(fp_line
			(start -4.500118 -1.599946)
			(end -3.6068 -1.599946)
			(stroke
				(width 0.1)
				(type default)
			)
			(layer "F.Fab")
		)
		(fp_line
			(start -4.99999 0)
			(end -4.99999 2.599944)
			(stroke
				(width 0.1)
				(type default)
			)
			(layer "F.Fab")
		)
		(fp_line
			(start 4.500118 2.100072)
			(end 1.999996 2.100072)
			(stroke
				(width 0.1)
				(type default)
			)
			(layer "F.Fab")
		)
		(fp_line
			(start 1.999996 2.100072)
			(end 1.999996 2.599944)
			(stroke
				(width 0.1)
				(type default)
			)
			(layer "F.Fab")
		)
		(fp_line
			(start -1.999996 2.100072)
			(end -4.500118 2.100072)
			(stroke
				(width 0.1)
				(type default)
			)
			(layer "F.Fab")
		)
		(fp_line
			(start -4.500118 2.100072)
			(end -4.500118 -1.599946)
			(stroke
				(width 0.1)
				(type default)
			)
			(layer "F.Fab")
		)
		(fp_line
			(start 4.99999 2.599944)
			(end 4.99999 -2.100072)
			(stroke
				(width 0.1)
				(type default)
			)
			(layer "F.Fab")
		)
		(fp_line
			(start -1.999996 2.599944)
			(end -1.999996 2.100072)
			(stroke
				(width 0.1)
				(type default)
			)
			(layer "F.Fab")
		)
		(fp_line
			(start -4.99999 2.599944)
			(end 4.99999 2.599944)
			(stroke
				(width 0.1)
				(type default)
			)
			(layer "F.Fab")
		)
		(fp_poly
			(pts
				(xy 5.715 0.899922) (xy 7.239 0.137922) (xy 7.239 1.661922)
			)
			(stroke
				(width 0)
				(type default)
			)
			(fill yes)
			(layer "F.Fab")
		)
		(fp_text user "1"
			(at 4.197096 -2.834132 0)
			(unlocked yes)
			(layer "F.SilkS")
			(effects
				(font
					(size 0.7874 0.5842)
					(thickness 0.1524)
				)
				(justify left)
			)
		)
		(fp_text user "4"
			(at -5.793994 1.24079 90)
			(unlocked yes)
			(layer "F.SilkS")
			(effects
				(font
					(size 0.7874 0.5842)
					(thickness 0.1524)
				)
				(justify left)
			)
		)
		(fp_text user "4"
			(at -4.571746 1.43383 0)
			(unlocked yes)
			(layer "B.SilkS")
			(effects
				(font
					(size 0.7874 0.5842)
					(thickness 0.1524)
				)
				(justify left mirror)
			)
		)
		(fp_text user "1"
			(at 4.340606 1.547622 0)
			(unlocked yes)
			(layer "B.SilkS")
			(effects
				(font
					(size 0.7874 0.5842)
					(thickness 0.1524)
				)
				(justify left mirror)
			)
		)
		(fp_text user "1"
			(at 4.4831 0.808203 90)
			(unlocked yes)
			(layer "B.Fab")
			(effects
				(font
					(size 0.786892 0.583946)
					(thickness 0.000001)
				)
				(justify left mirror)
			)
		)
		(fp_text user "4"
			(at -3.8989 0.808203 90)
			(unlocked yes)
			(layer "B.Fab")
			(effects
				(font
					(size 0.786892 0.583946)
					(thickness 0.000001)
				)
				(justify left mirror)
			)
		)
		(fp_text user "1"
			(at 5.0419 0.808203 90)
			(unlocked yes)
			(layer "F.Fab")
			(effects
				(font
					(size 0.786892 0.583946)
					(thickness 0.000001)
				)
				(justify left)
			)
		)
		(fp_text user "4"
			(at -6.0071 0.808203 90)
			(unlocked yes)
			(layer "F.Fab")
			(effects
				(font
					(size 0.786892 0.583946)
					(thickness 0.000001)
				)
				(justify left)
			)
		)
		(pad "" np_thru_hole circle
			(at -2.999994 -0.899922 90)
			(size 1.1938 1.1938)
			(drill 1.1938)
			(layers "*.Cu" "*.Mask")
			(clearance 0.381)
			(thermal_gap 0.381)
		)
		(pad "1" thru_hole rect
			(at 2.999994 0.899922 90)
			(size 1.3208 1.3208)
			(drill 0.9144)
			(layers "*.Cu" "*.Mask")
			(remove_unused_layers no)
			(net "P3V3_NODE1")
			(clearance 0.0508)
			(thermal_gap 0.0508)
			(padstack
				(mode front_inner_back)
				(layer "Inner"
					(shape circle)
					(size 1.3208 1.3208)
					(clearance 0.0508)
				)
				(layer "B.Cu"
					(shape rect)
					(size 1.3208 1.3208)
					(clearance 0.0508)
				)
			)
		)
		(pad "2" thru_hole circle
			(at 0.999998 0.899922 90)
			(size 1.3208 1.3208)
			(drill 0.9144)
			(layers "*.Cu" "*.Mask")
			(remove_unused_layers no)
			(net "UART_TX_P3")
			(clearance 0.0508)
			(thermal_gap 0.0508)
		)
		(pad "3" thru_hole circle
			(at -0.999998 0.899922 90)
			(size 1.3208 1.3208)
			(drill 0.9144)
			(layers "*.Cu" "*.Mask")
			(remove_unused_layers no)
			(net "UART_RX_P3")
			(clearance 0.0508)
			(thermal_gap 0.0508)
		)
		(pad "4" thru_hole circle
			(at -2.999994 0.899922 90)
			(size 1.3208 1.3208)
			(drill 0.9144)
			(layers "*.Cu" "*.Mask")
			(remove_unused_layers no)
			(net "GND")
			(clearance 0.0508)
			(thermal_gap 0.0508)
		)
		(zone
			(layers "F.Cu" "B.Cu" "In1.Cu" "In2.Cu" "In3.Cu" "In4.Cu" "In5.Cu" "In6.Cu"
				"In7.Cu" "In8.Cu"
			)
			(hatch none 0.5)
			(connect_pads
				(clearance 0)
			)
			(min_thickness 0.25)
			(keepout
				(tracks not_allowed)
				(vias allowed)
				(pads allowed)
				(copperpour not_allowed)
				(footprints allowed)
			)
			(placement
				(enabled no)
				(sheetname "")
			)
			(fill
				(thermal_gap 0.5)
				(thermal_bridge_width 0.5)
				(island_removal_mode 0)
			)
			(polygon
				(pts
					(arc
						(start 153.571956 -17.571212)
						(mid 153.869536 -16.852792)
						(end 154.587956 -16.555212)
					)
					(arc
						(start 154.587956 -16.555212)
						(mid 155.288416 -16.845352)
						(end 155.578556 -17.545812)
					)
					(arc
						(start 155.578556 -17.571212)
						(mid 154.575256 -18.574512)
						(end 153.571956 -17.571212)
					)
				)
			)
		)
	)
	(footprint ""
		(layer "F.Cu")
		(at 83.425538 -136.337294 -90)
		(property "Reference" "J23"
			(at -3.184652 -4.199128 90)
			(unlocked yes)
			(layer "F.SilkS")
			(effects
				(font
					(size 0.7874 0.5842)
					(thickness 0.1524)
				)
				(justify left)
			)
		)
		(property "Value" ""
			(at 0 0 270)
			(layer "F.Fab")
			(effects
				(font
					(size 1.27 1.27)
				)
			)
		)
		(duplicate_pad_numbers_are_jumpers no)
		(fp_poly
			(pts
				(xy 0.2794 0.907796) (xy 0.254 0.907796) (xy 0.254 1.0414) (xy -0.254 1.0414) (xy -0.254 1.034796)
				(xy -0.254 0.933196) (xy -0.2794 0.933196) (xy -0.2794 -0.133604) (xy -0.254 -0.133604) (xy -0.254 -0.235204)
				(xy 0.254 -0.235204) (xy 0.254 -0.133604) (xy 0.2794 -0.133604)
			)
			(stroke
				(width 0)
				(type default)
			)
			(fill no)
			(layer "F.CrtYd")
		)
		(pad "1" smd custom
			(at 0 -0.000254 270)
			(size 0.127 0.127)
			(layers "F.Cu" "F.Mask" "F.Paste")
			(net "P1V26_STB_NODE1_ADJ_S")
			(options
				(clearance outline)
				(anchor circle)
			)
			(primitives
				(gr_poly
					(pts
						(xy -0.127 0.508) (xy -0.127 -0.0508) (xy -0.254 -0.0508) (xy -0.254 -0.508) (xy 0.254 -0.508)
						(xy 0.254 -0.0508) (xy 0.127 -0.0508) (xy 0.127 0.508)
					)
					(width 0)
					(fill yes)
				)
			)
		)
		(pad "2" smd rect
			(at 0 0.799846)
			(size 0.4572 0.508)
			(layers "F.Cu" "F.Mask" "F.Paste")
			(net "P1V26_BMC_NODE1")
		)
		(zone
			(layer "F.Cu")
			(hatch none 0.5)
			(connect_pads
				(clearance 0)
			)
			(min_thickness 0.25)
			(keepout
				(tracks allowed)
				(vias not_allowed)
				(pads allowed)
				(copperpour not_allowed)
				(footprints allowed)
			)
			(placement
				(enabled no)
				(sheetname "")
			)
			(fill
				(thermal_gap 0.5)
				(thermal_bridge_width 0.5)
				(island_removal_mode 0)
			)
			(polygon
				(pts
					(xy 82.339942 -136.642094) (xy 82.339942 -136.032494) (xy 83.711542 -136.032494) (xy 83.711542 -136.642094)
				)
			)
		)
	)
	(footprint ""
		(layer "F.Cu")
		(at 64.622172 -156.431234)
		(property "Reference" "PC6"
			(at -32.142684 -4.459224 0)
			(unlocked yes)
			(layer "F.SilkS")
			(effects
				(font
					(size 0.7874 0.5842)
					(thickness 0.1524)
				)
				(justify left)
			)
		)
		(property "Value" ""
			(at 0 0 0)
			(layer "F.Fab")
			(effects
				(font
					(size 1.27 1.27)
				)
			)
		)
		(duplicate_pad_numbers_are_jumpers no)
		(fp_line
			(start -1.905 -0.8636)
			(end 1.905 -0.8636)
			(stroke
				(width 0.1524)
				(type default)
			)
			(layer "F.SilkS")
		)
		(fp_line
			(start -1.905 0.8636)
			(end -1.905 -0.8636)
			(stroke
				(width 0.1524)
				(type default)
			)
			(layer "F.SilkS")
		)
		(fp_line
			(start 0 0.8382)
			(end 0 -0.8382)
			(stroke
				(width 0.1524)
				(type default)
			)
			(layer "F.SilkS")
		)
		(fp_line
			(start 1.905 -0.8636)
			(end 1.905 0.8636)
			(stroke
				(width 0.1524)
				(type default)
			)
			(layer "F.SilkS")
		)
		(fp_line
			(start 1.905 0.8636)
			(end -1.905 0.8636)
			(stroke
				(width 0.1524)
				(type default)
			)
			(layer "F.SilkS")
		)
		(fp_rect
			(start -1.524 0.7366)
			(end 1.524 -0.7366)
			(stroke
				(width 0)
				(type default)
			)
			(fill no)
			(layer "F.CrtYd")
		)
		(pad "1" smd rect
			(at 0.94996 0)
			(size 1.1176 1.3716)
			(layers "F.Cu" "F.Mask" "F.Paste")
			(net "P5V_STB_NODE1")
		)
		(pad "2" smd rect
			(at -0.94996 0)
			(size 1.1176 1.3716)
			(layers "F.Cu" "F.Mask" "F.Paste")
			(net "GND")
		)
	)
	(footprint ""
		(layer "F.Cu")
		(at 38.39083 -118.112286 90)
		(property "Reference" "R1115"
			(at 0.167132 1.236472 90)
			(unlocked yes)
			(layer "F.SilkS")
			(effects
				(font
					(size 0.7874 0.5842)
					(thickness 0.1524)
				)
				(justify left)
			)
		)
		(property "Value" ""
			(at 0 0 90)
			(layer "F.Fab")
			(effects
				(font
					(size 1.27 1.27)
				)
			)
		)
		(duplicate_pad_numbers_are_jumpers no)
		(fp_line
			(start 0.7874 -0.4064)
			(end 0.7874 0.4064)
			(stroke
				(width 0.1524)
				(type default)
			)
			(layer "F.SilkS")
		)
		(fp_line
			(start -0.7874 -0.4064)
			(end 0.7874 -0.4064)
			(stroke
				(width 0.1524)
				(type default)
			)
			(layer "F.SilkS")
		)
		(fp_line
			(start 0.7874 0.4064)
			(end -0.7874 0.4064)
			(stroke
				(width 0.1524)
				(type default)
			)
			(layer "F.SilkS")
		)
		(fp_line
			(start -0.7874 0.4064)
			(end -0.7874 -0.4064)
			(stroke
				(width 0.1524)
				(type default)
			)
			(layer "F.SilkS")
		)
		(fp_poly
			(pts
				(xy -0.508 0.2794) (xy -0.508 0.2286) (xy -0.635 0.2286) (xy -0.635 -0.254) (xy -0.5334 -0.254)
				(xy -0.5334 -0.2794) (xy 0.5334 -0.2794) (xy 0.5334 -0.254) (xy 0.635 -0.254) (xy 0.635 0.254) (xy 0.5334 0.254)
				(xy 0.5334 0.2794)
			)
			(stroke
				(width 0)
				(type default)
			)
			(fill no)
			(layer "F.CrtYd")
		)
		(pad "1" smd rect
			(at 0.40005 0 90)
			(size 0.4572 0.508)
			(layers "F.Cu" "F.Mask" "F.Paste")
			(net "P5V_STB_NODE1")
		)
		(pad "2" smd rect
			(at -0.40005 0 90)
			(size 0.4572 0.508)
			(layers "F.Cu" "F.Mask" "F.Paste")
			(net "FM_CPLD_NODE1_P1V5_EN_LV")
		)
	)
	(footprint ""
		(layer "F.Cu")
		(at 44.49572 -173.717966)
		(property "Reference" "U92"
			(at 1.411224 132.150612 90)
			(unlocked yes)
			(layer "F.SilkS")
			(effects
				(font
					(size 0.7874 0.5842)
					(thickness 0.1524)
				)
			)
		)
		(property "Value" ""
			(at 0 0 0)
			(layer "F.Fab")
			(effects
				(font
					(size 1.27 1.27)
				)
			)
		)
		(duplicate_pad_numbers_are_jumpers no)
		(fp_line
			(start -1.651 -1.905)
			(end 1.651 -1.905)
			(stroke
				(width 0.1524)
				(type default)
			)
			(layer "F.SilkS")
		)
		(fp_line
			(start -1.651 1.905)
			(end -1.651 -1.905)
			(stroke
				(width 0.1524)
				(type default)
			)
			(layer "F.SilkS")
		)
		(fp_line
			(start 1.651 -1.905)
			(end 1.651 1.905)
			(stroke
				(width 0.1524)
				(type default)
			)
			(layer "F.SilkS")
		)
		(fp_line
			(start 1.651 1.905)
			(end -1.651 1.905)
			(stroke
				(width 0.1524)
				(type default)
			)
			(layer "F.SilkS")
		)
		(fp_poly
			(pts
				(xy -1.524 0.7112) (xy -1.524 1.7526) (xy -0.508 1.7526) (xy -0.508 0.6985) (xy 0.508 0.6985) (xy 0.508 1.7526)
				(xy 1.524 1.7526) (xy 1.524 0.6985) (xy 1.524 -0.6985) (xy 0.508 -0.6985) (xy 0.508 -1.7526) (xy -0.508 -1.7526)
				(xy -0.508 -0.6985) (xy -1.524 -0.6985) (xy -1.524 0.6985)
			)
			(stroke
				(width 0)
				(type default)
			)
			(fill no)
			(layer "F.CrtYd")
		)
		(fp_text user "G"
			(at -2.196846 1.442466 0)
			(unlocked yes)
			(layer "F.SilkS")
			(effects
				(font
					(size 0.635 0.4064)
					(thickness 0.1524)
				)
			)
		)
		(fp_text user "D"
			(at -0.823468 -2.367026 0)
			(unlocked yes)
			(layer "F.SilkS")
			(effects
				(font
					(size 0.635 0.4064)
					(thickness 0.1524)
				)
			)
		)
		(fp_text user "S"
			(at 1.830578 1.30175 0)
			(unlocked yes)
			(layer "F.SilkS")
			(effects
				(font
					(size 0.635 0.4064)
					(thickness 0.1524)
				)
			)
		)
		(pad "D" smd rect
			(at 0 -1.1176)
			(size 1.016 1.27)
			(layers "F.Cu" "F.Mask" "F.Paste")
			(net "P12V_AUX_EN")
		)
		(pad "G" smd rect
			(at -1.016 1.1176)
			(size 1.016 1.27)
			(layers "F.Cu" "F.Mask" "F.Paste")
			(net "PSU_DC_OK_N")
		)
		(pad "S" smd rect
			(at 1.016 1.1176)
			(size 1.016 1.27)
			(layers "F.Cu" "F.Mask" "F.Paste")
			(net "GND")
		)
	)
	(footprint ""
		(layer "F.Cu")
		(at 133.26745 -60.930282 -90)
		(property "Reference" "R653"
			(at 0.706882 -2.11582 90)
			(unlocked yes)
			(layer "F.SilkS")
			(effects
				(font
					(size 0.7874 0.5842)
					(thickness 0.1524)
				)
				(justify left)
			)
		)
		(property "Value" ""
			(at 0 0 270)
			(layer "F.Fab")
			(effects
				(font
					(size 1.27 1.27)
				)
			)
		)
		(duplicate_pad_numbers_are_jumpers no)
		(fp_line
			(start -0.7874 0.4064)
			(end -0.7874 -0.4064)
			(stroke
				(width 0.1524)
				(type default)
			)
			(layer "F.SilkS")
		)
		(fp_line
			(start 0.7874 0.4064)
			(end -0.7874 0.4064)
			(stroke
				(width 0.1524)
				(type default)
			)
			(layer "F.SilkS")
		)
		(fp_line
			(start -0.7874 -0.4064)
			(end 0.7874 -0.4064)
			(stroke
				(width 0.1524)
				(type default)
			)
			(layer "F.SilkS")
		)
		(fp_line
			(start 0.7874 -0.4064)
			(end 0.7874 0.4064)
			(stroke
				(width 0.1524)
				(type default)
			)
			(layer "F.SilkS")
		)
		(fp_poly
			(pts
				(xy -0.508 0.2794) (xy -0.508 0.2286) (xy -0.635 0.2286) (xy -0.635 -0.254) (xy -0.5334 -0.254)
				(xy -0.5334 -0.2794) (xy 0.5334 -0.2794) (xy 0.5334 -0.254) (xy 0.635 -0.254) (xy 0.635 0.254) (xy 0.5334 0.254)
				(xy 0.5334 0.2794)
			)
			(stroke
				(width 0)
				(type default)
			)
			(fill no)
			(layer "F.CrtYd")
		)
		(pad "1" smd rect
			(at 0.40005 0 270)
			(size 0.4572 0.508)
			(layers "F.Cu" "F.Mask" "F.Paste")
			(net "P3V3_NODE1")
		)
		(pad "2" smd rect
			(at -0.40005 0 270)
			(size 0.4572 0.508)
			(layers "F.Cu" "F.Mask" "F.Paste")
			(net "N21116716")
		)
	)
)
